# BASEBOARD_FAB2 (Tioga Pass) — schematic netlist excerpt (pin names and nets, part order shuffled) for the footprints in the layout excerpt that follows; sources: Cadence DE-HDL packaged netlist, KiCad conversion of Wiwynn_Tioga_Pass_MB.brd

R4U6  RES  100.0 1% EMPTY  pkg 0402  page 217 : A = VSENSE_PVDDQ_ABC_P ; B = VSENSE_PVDDQ_ABC_N
R3R15  RES  1.00K 1% CHIP  pkg 0402  page 189 : A = P3V3_STBY ; B = FM_JTAG_PLD_EN_DEBUG
R32W7  RES  2.0K 1% CHIP  pkg 0402  page 185 : A = P1V8_M2 ; B = SMB_M2_ALT_N

(kicad_pcb
	(version 20260206)
	(generator "pcbnew")
	(generator_version "10.0")
	(general
		(thickness 1.6)
		(legacy_teardrops no)
	)
	(paper "A4")
	(title_block
		(title "Wiwynn_Tioga_Pass_MB.brd")
		(comment 1 "Tioga Pass / footprints 2376-2378 of 4770")
	)
	(layers
		(0 "F.Cu" signal "TOP")
		(4 "In1.Cu" signal "L2GND")
		(6 "In2.Cu" signal "L3")
		(8 "In3.Cu" signal "L4GND")
		(10 "In4.Cu" signal "L5")
		(12 "In5.Cu" signal "L6GND")
		(14 "In6.Cu" signal "L7VCC")
		(16 "In7.Cu" signal "L8VCC")
		(18 "In8.Cu" signal "L9GND")
		(20 "In9.Cu" signal "L10")
		(22 "In10.Cu" signal "L11GND")
		(24 "In11.Cu" signal "L12")
		(26 "In12.Cu" signal "L13GND")
		(2 "B.Cu" signal "BOTTOM")
		(9 "F.Adhes" user "F.Adhesive")
		(11 "B.Adhes" user "B.Adhesive")
		(13 "F.Paste" user "Package Geometry/Pastemask Top")
		(15 "B.Paste" user "Package Geometry/Pastemask Bottom")
		(5 "F.SilkS" user "Ref Des/Silkscreen Top")
		(7 "B.SilkS" user "Ref Des/Silkscreen Bottom")
		(1 "F.Mask" user "Board Geometry/Soldermask Top")
		(3 "B.Mask" user "Board Geometry/Soldermask Bottom")
		(17 "Dwgs.User" user "User.Drawings")
		(19 "Cmts.User" user "User.Comments")
		(21 "Eco1.User" user "User.Eco1")
		(23 "Eco2.User" user "User.Eco2")
		(25 "Edge.Cuts" user "Board Geometry/Outline")
		(27 "Margin" user)
		(31 "F.CrtYd" user "Package Geometry/Place Bound Top")
		(29 "B.CrtYd" user "Package Geometry/Place Bound Bottom")
		(35 "F.Fab" user "Ref Des/Assembly Top")
		(33 "B.Fab" user "Ref Des/Assembly Bottom")
	)
	(footprint ""
		(layer "B.Cu")
		(at 371.05209 -65.411604 180)
		(property "Reference" "R3R15"
			(at 0 0 0)
			(layer "B.SilkS")
			(hide yes)
			(effects
				(font
					(size 1.27 1.27)
				)
				(justify mirror)
			)
		)
		(property "Value" ""
			(at 0 0 0)
			(layer "B.Fab")
			(effects
				(font
					(size 1.27 1.27)
				)
				(justify mirror)
			)
		)
		(duplicate_pad_numbers_are_jumpers no)
		(fp_poly
			(pts
				(xy 0.2794 -0.1016) (xy -0.2794 -0.1016) (xy -0.2794 0.9906) (xy 0.2794 0.9906)
			)
			(stroke
				(width 0)
				(type default)
			)
			(fill no)
			(layer "B.CrtYd")
		)
		(fp_line
			(start 0.2794 0.9906)
			(end -0.2794 0.9906)
			(stroke
				(width 0.1)
				(type default)
			)
			(layer "B.Fab")
		)
		(fp_line
			(start 0.2794 -0.1016)
			(end 0.2794 0.9906)
			(stroke
				(width 0.1)
				(type default)
			)
			(layer "B.Fab")
		)
		(fp_line
			(start -0.2794 0.9906)
			(end -0.2794 -0.1016)
			(stroke
				(width 0.1)
				(type default)
			)
			(layer "B.Fab")
		)
		(fp_line
			(start -0.2794 -0.1016)
			(end 0.2794 -0.1016)
			(stroke
				(width 0.1)
				(type default)
			)
			(layer "B.Fab")
		)
		(pad "1" smd rect
			(at 0 0)
			(size 0.508 0.508)
			(layers "B.Cu" "B.Mask" "B.Paste")
			(net "P3V3_STBY")
		)
		(pad "2" smd rect
			(at 0 0.889)
			(size 0.508 0.508)
			(layers "B.Cu" "B.Mask" "B.Paste")
			(net "FM_JTAG_PLD_EN_DEBUG")
		)
		(zone
			(layer "B.Cu")
			(hatch none 0.5)
			(connect_pads
				(clearance 0)
			)
			(min_thickness 0.25)
			(keepout
				(tracks not_allowed)
				(vias allowed)
				(pads allowed)
				(copperpour not_allowed)
				(footprints allowed)
			)
			(placement
				(enabled no)
				(sheetname "")
			)
			(fill
				(thermal_gap 0.5)
				(thermal_bridge_width 0.5)
				(island_removal_mode 0)
			)
			(polygon
				(pts
					(xy 370.79809 -66.046604) (xy 371.30609 -66.046604) (xy 371.30609 -65.665604) (xy 370.79809 -65.665604)
				)
			)
		)
		(zone
			(layer "B.Cu")
			(hatch none 0.5)
			(connect_pads
				(clearance 0)
			)
			(min_thickness 0.25)
			(keepout
				(tracks allowed)
				(vias not_allowed)
				(pads allowed)
				(copperpour not_allowed)
				(footprints allowed)
			)
			(placement
				(enabled no)
				(sheetname "")
			)
			(fill
				(thermal_gap 0.5)
				(thermal_bridge_width 0.5)
				(island_removal_mode 0)
			)
			(polygon
				(pts
					(xy 370.79809 -65.665604) (xy 371.30609 -65.665604) (xy 371.30609 -66.046604) (xy 370.79809 -66.046604)
				)
			)
		)
	)
	(footprint ""
		(layer "B.Cu")
		(at 276.9362 -29.337 90)
		(property "Reference" "R4U6"
			(at 0 0 90)
			(layer "B.SilkS")
			(hide yes)
			(effects
				(font
					(size 1.27 1.27)
				)
				(justify mirror)
			)
		)
		(property "Value" ""
			(at 0 0 90)
			(layer "B.Fab")
			(effects
				(font
					(size 1.27 1.27)
				)
				(justify mirror)
			)
		)
		(duplicate_pad_numbers_are_jumpers no)
		(fp_rect
			(start -0.2794 0.9906)
			(end 0.2794 -0.1016)
			(stroke
				(width 0)
				(type default)
			)
			(fill no)
			(layer "B.CrtYd")
		)
		(fp_line
			(start 0.2794 -0.1016)
			(end 0.2794 0.9906)
			(stroke
				(width 0.1)
				(type default)
			)
			(layer "B.Fab")
		)
		(fp_line
			(start -0.2794 -0.1016)
			(end 0.2794 -0.1016)
			(stroke
				(width 0.1)
				(type default)
			)
			(layer "B.Fab")
		)
		(fp_line
			(start 0.2794 0.9906)
			(end -0.2794 0.9906)
			(stroke
				(width 0.1)
				(type default)
			)
			(layer "B.Fab")
		)
		(fp_line
			(start -0.2794 0.9906)
			(end -0.2794 -0.1016)
			(stroke
				(width 0.1)
				(type default)
			)
			(layer "B.Fab")
		)
		(pad "1" smd rect
			(at 0 0 270)
			(size 0.508 0.508)
			(layers "B.Cu" "B.Mask" "B.Paste")
			(net "VSENSE_PVDDQ_ABC_P")
		)
		(pad "2" smd rect
			(at 0 0.889 270)
			(size 0.508 0.508)
			(layers "B.Cu" "B.Mask" "B.Paste")
			(net "VSENSE_PVDDQ_ABC_N")
		)
		(zone
			(layer "B.Cu")
			(hatch none 0.5)
			(connect_pads
				(clearance 0)
			)
			(min_thickness 0.25)
			(keepout
				(tracks allowed)
				(vias not_allowed)
				(pads allowed)
				(copperpour not_allowed)
				(footprints allowed)
			)
			(placement
				(enabled no)
				(sheetname "")
			)
			(fill
				(thermal_gap 0.5)
				(thermal_bridge_width 0.5)
				(island_removal_mode 0)
			)
			(polygon
				(pts
					(xy 277.5712 -29.083) (xy 277.5712 -29.591) (xy 277.1902 -29.591) (xy 277.1902 -29.083)
				)
			)
		)
	)
	(footprint ""
		(layer "B.Cu")
		(at 392.382756 -19.68119 180)
		(property "Reference" "R32W7"
			(at 0.8382 -0.67818 180)
			(unlocked yes)
			(layer "B.SilkS")
			(effects
				(font
					(size 0.4064 0.254)
					(thickness 0.1524)
				)
				(justify left mirror)
			)
		)
		(property "Value" ""
			(at 0 0 0)
			(layer "B.Fab")
			(effects
				(font
					(size 1.27 1.27)
				)
				(justify mirror)
			)
		)
		(duplicate_pad_numbers_are_jumpers no)
		(fp_poly
			(pts
				(xy 0.2794 -0.1016) (xy -0.2794 -0.1016) (xy -0.2794 0.9906) (xy 0.2794 0.9906)
			)
			(stroke
				(width 0)
				(type default)
			)
			(fill no)
			(layer "B.CrtYd")
		)
		(fp_line
			(start 0.2794 0.9906)
			(end -0.2794 0.9906)
			(stroke
				(width 0.1)
				(type default)
			)
			(layer "B.Fab")
		)
		(fp_line
			(start 0.2794 -0.1016)
			(end 0.2794 0.9906)
			(stroke
				(width 0.1)
				(type default)
			)
			(layer "B.Fab")
		)
		(fp_line
			(start -0.2794 0.9906)
			(end -0.2794 -0.1016)
			(stroke
				(width 0.1)
				(type default)
			)
			(layer "B.Fab")
		)
		(fp_line
			(start -0.2794 -0.1016)
			(end 0.2794 -0.1016)
			(stroke
				(width 0.1)
				(type default)
			)
			(layer "B.Fab")
		)
		(pad "1" smd rect
			(at 0 0)
			(size 0.508 0.508)
			(layers "B.Cu" "B.Mask" "B.Paste")
			(net "P1V8_M2")
		)
		(pad "2" smd rect
			(at 0 0.889)
			(size 0.508 0.508)
			(layers "B.Cu" "B.Mask" "B.Paste")
			(net "SMB_M2_ALT_N")
		)
		(zone
			(layer "B.Cu")
			(hatch none 0.5)
			(connect_pads
				(clearance 0)
			)
			(min_thickness 0.25)
			(keepout
				(tracks not_allowed)
				(vias allowed)
				(pads allowed)
				(copperpour not_allowed)
				(footprints allowed)
			)
			(placement
				(enabled no)
				(sheetname "")
			)
			(fill
				(thermal_gap 0.5)
				(thermal_bridge_width 0.5)
				(island_removal_mode 0)
			)
			(polygon
				(pts
					(xy 392.128756 -20.31619) (xy 392.636756 -20.31619) (xy 392.636756 -19.93519) (xy 392.128756 -19.93519)
				)
			)
		)
		(zone
			(layer "B.Cu")
			(hatch none 0.5)
			(connect_pads
				(clearance 0)
			)
			(min_thickness 0.25)
			(keepout
				(tracks allowed)
				(vias not_allowed)
				(pads allowed)
				(copperpour not_allowed)
				(footprints allowed)
			)
			(placement
				(enabled no)
				(sheetname "")
			)
			(fill
				(thermal_gap 0.5)
				(thermal_bridge_width 0.5)
				(island_removal_mode 0)
			)
			(polygon
				(pts
					(xy 392.128756 -19.93519) (xy 392.636756 -19.93519) (xy 392.636756 -20.31619) (xy 392.128756 -20.31619)
				)
			)
		)
	)
)
